(kicad_pcb
	(version 20260206)
	(generator "pcbnew")
	(generator_version "10.0")
	(general
		(thickness 1.6)
		(legacy_teardrops no)
	)
	(paper "A4")
	(title_block
		(title "Bryce Canyon_SCC_16316-1_OCP.brd")
		(comment 1 "Bryce Canyon / footprints 354-360 of 1561")
	)
	(layers
		(0 "F.Cu" signal "TOP")
		(4 "In1.Cu" signal "L2GND")
		(6 "In2.Cu" signal "L3")
		(8 "In3.Cu" signal "L4VCC")
		(10 "In4.Cu" signal "L5VCC")
		(12 "In5.Cu" signal "L6")
		(14 "In6.Cu" signal "L7GND")
		(2 "B.Cu" signal "BOTTOM")
		(9 "F.Adhes" user "F.Adhesive")
		(11 "B.Adhes" user "B.Adhesive")
		(13 "F.Paste" user "Package Geometry/Pastemask Top")
		(15 "B.Paste" user "Package Geometry/Pastemask Bottom")
		(5 "F.SilkS" user "Ref Des/Silkscreen Top")
		(7 "B.SilkS" user "Ref Des/Silkscreen Bottom")
		(1 "F.Mask" user "Board Geometry/Soldermask Top")
		(3 "B.Mask" user "Board Geometry/Soldermask Bottom")
		(17 "Dwgs.User" user "User.Drawings")
		(19 "Cmts.User" user "User.Comments")
		(21 "Eco1.User" user "User.Eco1")
		(23 "Eco2.User" user "User.Eco2")
		(25 "Edge.Cuts" user "Board Geometry/Outline")
		(27 "Margin" user)
		(31 "F.CrtYd" user "Package Geometry/Place Bound Top")
		(29 "B.CrtYd" user "Package Geometry/Place Bound Bottom")
		(35 "F.Fab" user "Ref Des/Assembly Top")
		(33 "B.Fab" user "Ref Des/Assembly Bottom")
	)
	(footprint ""
		(layer "F.Cu")
		(at 181.580282 -104.651556 90)
		(property "Reference" "C395"
			(at 0 0 90)
			(layer "F.SilkS")
			(hide yes)
			(effects
				(font
					(size 1.27 1.27)
				)
			)
		)
		(property "Value" "SC100U6D3V6MX-GP"
			(at -0.0762 -5.1308 90)
			(unlocked yes)
			(layer "F.Fab")
			(hide yes)
			(effects
				(font
					(size 1.016 1.016)
					(thickness 0.1524)
				)
			)
		)
		(property "Device Type" "C1206H71"
			(at -0.127 -6.6548 90)
			(unlocked yes)
			(layer "F.Fab")
			(hide yes)
			(effects
				(font
					(size 1.016 1.016)
					(thickness 0.1524)
				)
			)
		)
		(duplicate_pad_numbers_are_jumpers no)
		(fp_line
			(start 1.016 -2.2352)
			(end 1.016 -0.8382)
			(stroke
				(width 0.1524)
				(type default)
			)
			(layer "F.SilkS")
		)
		(fp_line
			(start -1.016 -2.2352)
			(end 1.016 -2.2352)
			(stroke
				(width 0.1524)
				(type default)
			)
			(layer "F.SilkS")
		)
		(fp_line
			(start -1.016 -0.8382)
			(end -1.016 -2.2352)
			(stroke
				(width 0.1524)
				(type default)
			)
			(layer "F.SilkS")
		)
		(fp_line
			(start 1.016 0.8382)
			(end 1.016 2.2352)
			(stroke
				(width 0.1524)
				(type default)
			)
			(layer "F.SilkS")
		)
		(fp_line
			(start 1.016 2.2352)
			(end -1.016 2.2352)
			(stroke
				(width 0.1524)
				(type default)
			)
			(layer "F.SilkS")
		)
		(fp_line
			(start -1.016 2.2352)
			(end -1.016 0.8382)
			(stroke
				(width 0.1524)
				(type default)
			)
			(layer "F.SilkS")
		)
		(fp_rect
			(start -1.0922 2.3114)
			(end 1.0922 -2.3114)
			(stroke
				(width 0)
				(type default)
			)
			(fill no)
			(layer "F.CrtYd")
		)
		(fp_poly
			(pts
				(xy 1.0922 -2.3114) (xy 1.0922 2.3114) (xy -1.0922 2.3114) (xy -1.0922 -2.3114)
			)
			(stroke
				(width 0)
				(type default)
			)
			(fill no)
			(layer "F.Fab")
		)
		(pad "1" smd rect
			(at 0 -1.397 90)
			(size 1.651 1.27)
			(layers "F.Cu" "F.Mask" "F.Paste")
			(net "GND")
		)
		(pad "2" smd rect
			(at 0 1.397 90)
			(size 1.651 1.27)
			(layers "F.Cu" "F.Mask" "F.Paste")
			(net "SAS0_AVDD")
		)
	)
	(footprint ""
		(layer "F.Cu")
		(at 9.500108 -131.430014)
		(property "Reference" "LHOLE1"
			(at 0 0 0)
			(layer "F.SilkS")
			(hide yes)
			(effects
				(font
					(size 1.27 1.27)
				)
			)
		)
		(property "Value" "HOLE709R146-3P-S3-GP"
			(at -5.5626 -0.9652 0)
			(unlocked yes)
			(layer "F.Fab")
			(hide yes)
			(effects
				(font
					(size 1.016 1.016)
					(thickness 0.1524)
				)
			)
		)
		(property "Device Type" "HOLE709R146-3P-S3"
			(at -5.5626 -2.4892 0)
			(unlocked yes)
			(layer "F.Fab")
			(hide yes)
			(effects
				(font
					(size 1.016 1.016)
					(thickness 0.1524)
				)
			)
		)
		(duplicate_pad_numbers_are_jumpers no)
		(fp_poly
			(pts
				(arc
					(start -4.8006 -7.975854)
					(mid 9.309136 0)
					(end -4.8006 7.975854)
				)
			)
			(stroke
				(width 0)
				(type default)
			)
			(fill no)
			(layer "B.CrtYd")
		)
		(fp_poly
			(pts
				(arc
					(start -4.8006 -7.975854)
					(mid 9.309136 0)
					(end -4.8006 7.975854)
				)
			)
			(stroke
				(width 0)
				(type default)
			)
			(fill no)
			(layer "F.CrtYd")
		)
		(fp_poly
			(pts
				(arc
					(start -4.8006 -7.975854)
					(mid 9.309136 0)
					(end -4.8006 7.975854)
				)
			)
			(stroke
				(width 0)
				(type default)
			)
			(fill no)
			(layer "B.Fab")
		)
		(fp_poly
			(pts
				(arc
					(start -4.8006 -7.975854)
					(mid 9.309136 0)
					(end -4.8006 7.975854)
				)
			)
			(stroke
				(width 0)
				(type default)
			)
			(fill no)
			(layer "F.Fab")
		)
		(pad "1" thru_hole circle
			(at 0 -4.500118)
			(size 2.5146 2.5146)
			(drill 2.1082)
			(layers "*.Cu" "*.Mask")
			(remove_unused_layers no)
			(net "GND")
			(clearance 0.1524)
			(thermal_gap 0.1524)
		)
		(pad "2" thru_hole custom
			(at 0 0)
			(size 3.374898 3.374898)
			(drill 3.7084)
			(layers "*.Cu" "*.Mask")
			(remove_unused_layers no)
			(net "GND")
			(clearance -4.38785)
			(thermal_gap 0.3048)
			(options
				(clearance outline)
				(anchor circle)
			)
			(primitives
				(gr_poly
					(pts
						(arc
							(start -6.75005 -7.80161)
							(mid 6.750045 0)
							(end -6.75005 7.80161)
						)
					)
					(width 0)
					(fill yes)
				)
			)
			(padstack
				(mode front_inner_back)
				(layer "Inner"
					(shape circle)
					(size 4.1148 4.1148)
					(clearance 0.3048)
				)
				(layer "B.Cu"
					(shape custom)
					(size 3.374898 3.374898)
					(options
						(anchor circle)
					)
					(primitives
						(gr_poly
							(pts
								(arc
									(start -6.75005 -7.80161)
									(mid 6.750045 0)
									(end -6.75005 7.80161)
								)
							)
							(width 0)
							(fill yes)
						)
					)
					(clearance -4.38785)
				)
			)
		)
		(pad "3" thru_hole circle
			(at 0 4.500118)
			(size 1.9812 1.9812)
			(drill 1.5748)
			(layers "*.Cu" "*.Mask")
			(remove_unused_layers no)
			(net "GND")
			(clearance 0.1524)
			(thermal_gap 0.1524)
		)
	)
	(footprint ""
		(layer "F.Cu")
		(at 147.438618 -50.468022 102)
		(property "Reference" "C342"
			(at 0 0 102)
			(layer "F.SilkS")
			(hide yes)
			(effects
				(font
					(size 1.27 1.27)
				)
			)
		)
		(property "Value" "SCD01U16V1KX-GP"
			(at -2.832244 -1.740078 102)
			(unlocked yes)
			(layer "F.Fab")
			(hide yes)
			(effects
				(font
					(size 1.016 1.016)
					(thickness 0.1524)
				)
			)
		)
		(property "Device Type" "C0201H13"
			(at -2.832121 -3.264082 102)
			(unlocked yes)
			(layer "F.Fab")
			(hide yes)
			(effects
				(font
					(size 1.016 1.016)
					(thickness 0.1524)
				)
			)
		)
		(duplicate_pad_numbers_are_jumpers no)
		(fp_poly
			(pts
				(xy -0.279454 -0.647706) (xy 0.279346 -0.647706) (xy 0.279346 0.647694) (xy -0.279454 0.647694)
			)
			(stroke
				(width 0)
				(type default)
			)
			(fill no)
			(layer "F.CrtYd")
		)
		(fp_poly
			(pts
				(xy -0.279454 -0.647706) (xy 0.279346 -0.647706) (xy 0.279346 0.647694) (xy -0.279454 0.647694)
			)
			(stroke
				(width 0)
				(type default)
			)
			(fill no)
			(layer "F.Fab")
		)
		(pad "1" smd custom
			(at -0.000001 -0.2794 102)
			(size 0.0762 0.0762)
			(layers "F.Cu" "F.Mask" "F.Paste")
			(net "PHY_SCC_TO_IOC_46_DN")
			(options
				(clearance outline)
				(anchor circle)
			)
			(primitives
				(gr_poly
					(pts
						(arc
							(start 0.1524 -0.127)
							(mid 0.137521 -0.162921)
							(end 0.1016 -0.1778)
						)
						(arc
							(start -0.1016 -0.1778)
							(mid -0.137521 -0.162921)
							(end -0.1524 -0.127)
						)
						(arc
							(start -0.1524 0.127)
							(mid -0.137521 0.162921)
							(end -0.1016 0.1778)
						)
						(arc
							(start 0.1016 0.1778)
							(mid 0.137521 0.162921)
							(end 0.1524 0.127)
						)
					)
					(width 0)
					(fill yes)
				)
			)
		)
		(pad "2" smd custom
			(at 0.000001 0.2794 102)
			(size 0.0762 0.0762)
			(layers "F.Cu" "F.Mask" "F.Paste")
			(net "PHY_SCC_TO_IOC_C_46_DN")
			(options
				(clearance outline)
				(anchor circle)
			)
			(primitives
				(gr_poly
					(pts
						(arc
							(start 0.1524 -0.127)
							(mid 0.137521 -0.162921)
							(end 0.1016 -0.1778)
						)
						(arc
							(start -0.1016 -0.1778)
							(mid -0.137521 -0.162921)
							(end -0.1524 -0.127)
						)
						(arc
							(start -0.1524 0.127)
							(mid -0.137521 0.162921)
							(end -0.1016 0.1778)
						)
						(arc
							(start 0.1016 0.1778)
							(mid 0.137521 0.162921)
							(end 0.1524 0.127)
						)
					)
					(width 0)
					(fill yes)
				)
			)
		)
	)
	(footprint ""
		(layer "F.Cu")
		(at 88.543638 -55.58536 180)
		(property "Reference" "C110"
			(at 0 0 180)
			(layer "F.SilkS")
			(hide yes)
			(effects
				(font
					(size 1.27 1.27)
				)
			)
		)
		(property "Value" "SC15P50V2JN-2-GP"
			(at 1.1811 -2.7051 180)
			(unlocked yes)
			(layer "F.Fab")
			(hide yes)
			(effects
				(font
					(size 1.016 1.016)
					(thickness 0.1524)
				)
			)
		)
		(property "Device Type" "C402H22"
			(at 1.1811 -4.2291 180)
			(unlocked yes)
			(layer "F.Fab")
			(hide yes)
			(effects
				(font
					(size 1.016 1.016)
					(thickness 0.1524)
				)
			)
		)
		(duplicate_pad_numbers_are_jumpers no)
		(fp_rect
			(start -0.4318 0.9525)
			(end 0.4318 -0.9525)
			(stroke
				(width 0)
				(type default)
			)
			(fill no)
			(layer "F.CrtYd")
		)
		(fp_rect
			(start -0.4318 0.9525)
			(end 0.4318 -0.9525)
			(stroke
				(width 0)
				(type default)
			)
			(fill no)
			(layer "F.Fab")
		)
		(pad "1" smd custom
			(at 0 -0.4445 180)
			(size 0.1524 0.1524)
			(layers "F.Cu" "F.Mask" "F.Paste")
			(net "EXP_REF_CLK_P")
			(options
				(clearance outline)
				(anchor circle)
			)
			(primitives
				(gr_poly
					(pts
						(arc
							(start 0.3048 -0.2032)
							(mid 0.275042 -0.275042)
							(end 0.2032 -0.3048)
						)
						(arc
							(start -0.2032 -0.3048)
							(mid -0.275042 -0.275042)
							(end -0.3048 -0.2032)
						)
						(arc
							(start -0.3048 0.2032)
							(mid -0.275042 0.275042)
							(end -0.2032 0.3048)
						)
						(arc
							(start 0.2032 0.3048)
							(mid 0.275042 0.275042)
							(end 0.3048 0.2032)
						)
					)
					(width 0)
					(fill yes)
				)
			)
		)
		(pad "2" smd custom
			(at 0 0.4445 180)
			(size 0.1524 0.1524)
			(layers "F.Cu" "F.Mask" "F.Paste")
			(net "GND")
			(options
				(clearance outline)
				(anchor circle)
			)
			(primitives
				(gr_poly
					(pts
						(arc
							(start 0.3048 -0.2032)
							(mid 0.275042 -0.275042)
							(end 0.2032 -0.3048)
						)
						(arc
							(start -0.2032 -0.3048)
							(mid -0.275042 -0.275042)
							(end -0.3048 -0.2032)
						)
						(arc
							(start -0.3048 0.2032)
							(mid -0.275042 0.275042)
							(end -0.2032 0.3048)
						)
						(arc
							(start 0.2032 0.3048)
							(mid 0.275042 0.275042)
							(end 0.3048 0.2032)
						)
					)
					(width 0)
					(fill yes)
				)
			)
		)
	)
	(footprint ""
		(layer "F.Cu")
		(at 151.257 -88.1253 -90)
		(property "Reference" "R445"
			(at 0 0 270)
			(layer "F.SilkS")
			(hide yes)
			(effects
				(font
					(size 1.27 1.27)
				)
			)
		)
		(property "Value" "1KR2F-3-GP"
			(at 0.064008 -3.993896 270)
			(unlocked yes)
			(layer "F.Fab")
			(hide yes)
			(effects
				(font
					(size 1.016 1.016)
					(thickness 0.1524)
				)
			)
		)
		(property "Device Type" "R402H16"
			(at 0.064008 -5.517896 270)
			(unlocked yes)
			(layer "F.Fab")
			(hide yes)
			(effects
				(font
					(size 1.016 1.016)
					(thickness 0.1524)
				)
			)
		)
		(duplicate_pad_numbers_are_jumpers no)
		(fp_line
			(start -0.508 -0.9398)
			(end -0.508 0.9398)
			(stroke
				(width 0.1524)
				(type default)
			)
			(layer "F.SilkS")
		)
		(fp_line
			(start 0.508 -0.9398)
			(end -0.508 -0.9398)
			(stroke
				(width 0.1524)
				(type default)
			)
			(layer "F.SilkS")
		)
		(fp_rect
			(start -0.508 0.9398)
			(end 0.508 -0.9398)
			(stroke
				(width 0)
				(type default)
			)
			(fill no)
			(layer "F.CrtYd")
		)
		(fp_rect
			(start -0.508 0.9398)
			(end 0.508 -0.9398)
			(stroke
				(width 0)
				(type default)
			)
			(fill no)
			(layer "F.Fab")
		)
		(pad "1" smd custom
			(at 0 -0.4445 270)
			(size 0.1397 0.1397)
			(layers "F.Cu" "F.Mask" "F.Paste")
			(net "P3V3")
			(options
				(clearance outline)
				(anchor circle)
			)
			(primitives
				(gr_poly
					(pts
						(arc
							(start -0.1778 -0.2794)
							(mid -0.249642 -0.249642)
							(end -0.2794 -0.1778)
						)
						(arc
							(start -0.2794 0.1778)
							(mid -0.249642 0.249642)
							(end -0.1778 0.2794)
						)
						(arc
							(start 0.1778 0.2794)
							(mid 0.249642 0.249642)
							(end 0.2794 0.1778)
						)
						(arc
							(start 0.2794 -0.1778)
							(mid 0.249642 -0.249642)
							(end 0.1778 -0.2794)
						)
					)
					(width 0)
					(fill yes)
				)
			)
		)
		(pad "2" smd custom
			(at 0 0.4445 270)
			(size 0.1397 0.1397)
			(layers "F.Cu" "F.Mask" "F.Paste")
			(net "P3V3_SENSE")
			(options
				(clearance outline)
				(anchor circle)
			)
			(primitives
				(gr_poly
					(pts
						(arc
							(start -0.1778 -0.2794)
							(mid -0.249642 -0.249642)
							(end -0.2794 -0.1778)
						)
						(arc
							(start -0.2794 0.1778)
							(mid -0.249642 0.249642)
							(end -0.1778 0.2794)
						)
						(arc
							(start 0.1778 0.2794)
							(mid 0.249642 0.249642)
							(end 0.2794 0.1778)
						)
						(arc
							(start 0.2794 -0.1778)
							(mid 0.249642 -0.249642)
							(end 0.1778 -0.2794)
						)
					)
					(width 0)
					(fill yes)
				)
			)
		)
	)
	(footprint ""
		(layer "F.Cu")
		(at 142.778226 -63.791084 -90)
		(property "Reference" "C33"
			(at 0 0 270)
			(layer "F.SilkS")
			(hide yes)
			(effects
				(font
					(size 1.27 1.27)
				)
			)
		)
		(property "Value" "SCD01U16V1KX-GP"
			(at -2.8321 -1.7399 270)
			(unlocked yes)
			(layer "F.Fab")
			(hide yes)
			(effects
				(font
					(size 1.016 1.016)
					(thickness 0.1524)
				)
			)
		)
		(property "Device Type" "C0201H13"
			(at -2.8321 -3.2639 270)
			(unlocked yes)
			(layer "F.Fab")
			(hide yes)
			(effects
				(font
					(size 1.016 1.016)
					(thickness 0.1524)
				)
			)
		)
		(duplicate_pad_numbers_are_jumpers no)
		(fp_rect
			(start -0.2794 0.6477)
			(end 0.2794 -0.6477)
			(stroke
				(width 0)
				(type default)
			)
			(fill no)
			(layer "F.CrtYd")
		)
		(fp_rect
			(start -0.2794 0.6477)
			(end 0.2794 -0.6477)
			(stroke
				(width 0)
				(type default)
			)
			(fill no)
			(layer "F.Fab")
		)
		(pad "1" smd custom
			(at 0 -0.2794 270)
			(size 0.0762 0.0762)
			(layers "F.Cu" "F.Mask" "F.Paste")
			(net "PHY_IOC_TO_SCC_47_DP")
			(options
				(clearance outline)
				(anchor circle)
			)
			(primitives
				(gr_poly
					(pts
						(arc
							(start 0.1524 -0.127)
							(mid 0.137521 -0.162921)
							(end 0.1016 -0.1778)
						)
						(arc
							(start -0.1016 -0.1778)
							(mid -0.137521 -0.162921)
							(end -0.1524 -0.127)
						)
						(arc
							(start -0.1524 0.127)
							(mid -0.137521 0.162921)
							(end -0.1016 0.1778)
						)
						(arc
							(start 0.1016 0.1778)
							(mid 0.137521 0.162921)
							(end 0.1524 0.127)
						)
					)
					(width 0)
					(fill yes)
				)
			)
		)
		(pad "2" smd custom
			(at 0 0.2794 270)
			(size 0.0762 0.0762)
			(layers "F.Cu" "F.Mask" "F.Paste")
			(net "PHY_IOC_TO_SCC_C_47_DP")
			(options
				(clearance outline)
				(anchor circle)
			)
			(primitives
				(gr_poly
					(pts
						(arc
							(start 0.1524 -0.127)
							(mid 0.137521 -0.162921)
							(end 0.1016 -0.1778)
						)
						(arc
							(start -0.1016 -0.1778)
							(mid -0.137521 -0.162921)
							(end -0.1524 -0.127)
						)
						(arc
							(start -0.1524 0.127)
							(mid -0.137521 0.162921)
							(end -0.1016 0.1778)
						)
						(arc
							(start 0.1016 0.1778)
							(mid 0.137521 0.162921)
							(end 0.1524 0.127)
						)
					)
					(width 0)
					(fill yes)
				)
			)
		)
	)
	(footprint ""
		(layer "F.Cu")
		(at 191.994282 -81.707736 90)
		(property "Reference" "R368"
			(at 0 0 90)
			(layer "F.SilkS")
			(hide yes)
			(effects
				(font
					(size 1.27 1.27)
				)
			)
		)
		(property "Value" "4K7R2F-GP"
			(at 0.064008 -3.993896 90)
			(unlocked yes)
			(layer "F.Fab")
			(hide yes)
			(effects
				(font
					(size 1.016 1.016)
					(thickness 0.1524)
				)
			)
		)
		(property "Device Type" "R402H16"
			(at 0.064008 -5.517896 90)
			(unlocked yes)
			(layer "F.Fab")
			(hide yes)
			(effects
				(font
					(size 1.016 1.016)
					(thickness 0.1524)
				)
			)
		)
		(duplicate_pad_numbers_are_jumpers no)
		(fp_line
			(start 0.508 -0.9398)
			(end -0.508 -0.9398)
			(stroke
				(width 0.1524)
				(type default)
			)
			(layer "F.SilkS")
		)
		(fp_line
			(start -0.508 -0.9398)
			(end -0.508 0.9398)
			(stroke
				(width 0.1524)
				(type default)
			)
			(layer "F.SilkS")
		)
		(fp_rect
			(start -0.508 0.9398)
			(end 0.508 -0.9398)
			(stroke
				(width 0)
				(type default)
			)
			(fill no)
			(layer "F.CrtYd")
		)
		(fp_rect
			(start -0.508 0.9398)
			(end 0.508 -0.9398)
			(stroke
				(width 0)
				(type default)
			)
			(fill no)
			(layer "F.Fab")
		)
		(pad "1" smd custom
			(at 0 -0.4445 90)
			(size 0.1397 0.1397)
			(layers "F.Cu" "F.Mask" "F.Paste")
			(net "P3V3")
			(options
				(clearance outline)
				(anchor circle)
			)
			(primitives
				(gr_poly
					(pts
						(arc
							(start -0.1778 -0.2794)
							(mid -0.249642 -0.249642)
							(end -0.2794 -0.1778)
						)
						(arc
							(start -0.2794 0.1778)
							(mid -0.249642 0.249642)
							(end -0.1778 0.2794)
						)
						(arc
							(start 0.1778 0.2794)
							(mid 0.249642 0.249642)
							(end 0.2794 0.1778)
						)
						(arc
							(start 0.2794 -0.1778)
							(mid 0.249642 -0.249642)
							(end 0.1778 -0.2794)
						)
					)
					(width 0)
					(fill yes)
				)
			)
		)
		(pad "2" smd custom
			(at 0 0.4445 90)
			(size 0.1397 0.1397)
			(layers "F.Cu" "F.Mask" "F.Paste")
			(net "TEMP2_A2")
			(options
				(clearance outline)
				(anchor circle)
			)
			(primitives
				(gr_poly
					(pts
						(arc
							(start -0.1778 -0.2794)
							(mid -0.249642 -0.249642)
							(end -0.2794 -0.1778)
						)
						(arc
							(start -0.2794 0.1778)
							(mid -0.249642 0.249642)
							(end -0.1778 0.2794)
						)
						(arc
							(start 0.1778 0.2794)
							(mid 0.249642 0.249642)
							(end 0.2794 0.1778)
						)
						(arc
							(start 0.2794 -0.1778)
							(mid 0.249642 -0.249642)
							(end 0.1778 -0.2794)
						)
					)
					(width 0)
					(fill yes)
				)
			)
		)
	)
)
